# BASEBOARD_FAB2 (Tioga Pass) — schematic netlist excerpt (pin names and nets, part order shuffled) for the footprints in the layout excerpt that follows; sources: Cadence DE-HDL packaged netlist, KiCad conversion of Wiwynn_Tioga_Pass_MB.brd

R2N7  RES  4.75K 1% CHIP  pkg 0402  page 133 : A = P3V3_STBY ; B = IRQ_BOARD_BMC_ALERT_N
C1C12  CAP  0.220UF 16V 10% X7R  pkg 0402  page 210 : A = VR_PVSA_CPU1_BOOT ; B = VR_PVSA_CPU1_PHASE
R8D23  RES  20.0 1% CHIP  pkg 0402  page 167 : A = SMB_SENSOR_STBY_LVC3_SDA_R2 ; B = SMB_SENSOR_STBY_LVC3_SDA

(kicad_pcb
	(version 20260206)
	(generator "pcbnew")
	(generator_version "10.0")
	(general
		(thickness 1.6)
		(legacy_teardrops no)
	)
	(paper "A4")
	(title_block
		(title "Wiwynn_Tioga_Pass_MB.brd")
		(comment 1 "Tioga Pass / footprints 2019-2021 of 4770")
	)
	(layers
		(0 "F.Cu" signal "TOP")
		(4 "In1.Cu" signal "L2GND")
		(6 "In2.Cu" signal "L3")
		(8 "In3.Cu" signal "L4GND")
		(10 "In4.Cu" signal "L5")
		(12 "In5.Cu" signal "L6GND")
		(14 "In6.Cu" signal "L7VCC")
		(16 "In7.Cu" signal "L8VCC")
		(18 "In8.Cu" signal "L9GND")
		(20 "In9.Cu" signal "L10")
		(22 "In10.Cu" signal "L11GND")
		(24 "In11.Cu" signal "L12")
		(26 "In12.Cu" signal "L13GND")
		(2 "B.Cu" signal "BOTTOM")
		(9 "F.Adhes" user "F.Adhesive")
		(11 "B.Adhes" user "B.Adhesive")
		(13 "F.Paste" user "Package Geometry/Pastemask Top")
		(15 "B.Paste" user "Package Geometry/Pastemask Bottom")
		(5 "F.SilkS" user "Ref Des/Silkscreen Top")
		(7 "B.SilkS" user "Ref Des/Silkscreen Bottom")
		(1 "F.Mask" user "Board Geometry/Soldermask Top")
		(3 "B.Mask" user "Board Geometry/Soldermask Bottom")
		(17 "Dwgs.User" user "User.Drawings")
		(19 "Cmts.User" user "User.Comments")
		(21 "Eco1.User" user "User.Eco1")
		(23 "Eco2.User" user "User.Eco2")
		(25 "Edge.Cuts" user "Board Geometry/Outline")
		(27 "Margin" user)
		(31 "F.CrtYd" user "Package Geometry/Place Bound Top")
		(29 "B.CrtYd" user "Package Geometry/Place Bound Bottom")
		(35 "F.Fab" user "Ref Des/Assembly Top")
		(33 "B.Fab" user "Ref Des/Assembly Bottom")
	)
	(footprint ""
		(layer "F.Cu")
		(at 410.226256 -57.26684 90)
		(property "Reference" "R8D23"
			(at 0 0 90)
			(layer "F.SilkS")
			(hide yes)
			(effects
				(font
					(size 1.27 1.27)
				)
			)
		)
		(property "Value" ""
			(at 0 0 90)
			(layer "F.Fab")
			(effects
				(font
					(size 1.27 1.27)
				)
			)
		)
		(duplicate_pad_numbers_are_jumpers no)
		(fp_poly
			(pts
				(xy -0.2794 -0.1016) (xy 0.2794 -0.1016) (xy 0.2794 0.9906) (xy -0.2794 0.9906)
			)
			(stroke
				(width 0)
				(type default)
			)
			(fill no)
			(layer "F.CrtYd")
		)
		(fp_line
			(start 0.2794 -0.1016)
			(end -0.2794 -0.1016)
			(stroke
				(width 0.1)
				(type default)
			)
			(layer "F.Fab")
		)
		(fp_line
			(start -0.2794 -0.1016)
			(end -0.2794 0.9906)
			(stroke
				(width 0.1)
				(type default)
			)
			(layer "F.Fab")
		)
		(fp_line
			(start 0.2794 0.9906)
			(end 0.2794 -0.1016)
			(stroke
				(width 0.1)
				(type default)
			)
			(layer "F.Fab")
		)
		(fp_line
			(start -0.2794 0.9906)
			(end 0.2794 0.9906)
			(stroke
				(width 0.1)
				(type default)
			)
			(layer "F.Fab")
		)
		(pad "1" smd rect
			(at 0 0 90)
			(size 0.508 0.508)
			(layers "F.Cu" "F.Mask" "F.Paste")
			(net "SMB_SENSOR_STBY_LVC3_SDA_R2")
		)
		(pad "2" smd rect
			(at 0 0.889 90)
			(size 0.508 0.508)
			(layers "F.Cu" "F.Mask" "F.Paste")
			(net "SMB_SENSOR_STBY_LVC3_SDA")
		)
		(zone
			(layer "F.Cu")
			(hatch none 0.5)
			(connect_pads
				(clearance 0)
			)
			(min_thickness 0.25)
			(keepout
				(tracks allowed)
				(vias not_allowed)
				(pads allowed)
				(copperpour not_allowed)
				(footprints allowed)
			)
			(placement
				(enabled no)
				(sheetname "")
			)
			(fill
				(thermal_gap 0.5)
				(thermal_bridge_width 0.5)
				(island_removal_mode 0)
			)
			(polygon
				(pts
					(xy 410.480256 -57.01284) (xy 410.480256 -57.52084) (xy 410.861256 -57.52084) (xy 410.861256 -57.01284)
				)
			)
		)
		(zone
			(layer "F.Cu")
			(hatch none 0.5)
			(connect_pads
				(clearance 0)
			)
			(min_thickness 0.25)
			(keepout
				(tracks not_allowed)
				(vias allowed)
				(pads allowed)
				(copperpour not_allowed)
				(footprints allowed)
			)
			(placement
				(enabled no)
				(sheetname "")
			)
			(fill
				(thermal_gap 0.5)
				(thermal_bridge_width 0.5)
				(island_removal_mode 0)
			)
			(polygon
				(pts
					(xy 410.861256 -57.01284) (xy 410.861256 -57.52084) (xy 410.480256 -57.52084) (xy 410.480256 -57.01284)
				)
			)
		)
	)
	(footprint ""
		(layer "F.Cu")
		(at 407.9875 -104.648 90)
		(property "Reference" "R2N7"
			(at 0 0 90)
			(layer "F.SilkS")
			(hide yes)
			(effects
				(font
					(size 1.27 1.27)
				)
			)
		)
		(property "Value" ""
			(at 0 0 90)
			(layer "F.Fab")
			(effects
				(font
					(size 1.27 1.27)
				)
			)
		)
		(duplicate_pad_numbers_are_jumpers no)
		(fp_poly
			(pts
				(xy -0.2794 -0.1016) (xy 0.2794 -0.1016) (xy 0.2794 0.9906) (xy -0.2794 0.9906)
			)
			(stroke
				(width 0)
				(type default)
			)
			(fill no)
			(layer "F.CrtYd")
		)
		(fp_line
			(start 0.2794 -0.1016)
			(end -0.2794 -0.1016)
			(stroke
				(width 0.1)
				(type default)
			)
			(layer "F.Fab")
		)
		(fp_line
			(start -0.2794 -0.1016)
			(end -0.2794 0.9906)
			(stroke
				(width 0.1)
				(type default)
			)
			(layer "F.Fab")
		)
		(fp_line
			(start 0.2794 0.9906)
			(end 0.2794 -0.1016)
			(stroke
				(width 0.1)
				(type default)
			)
			(layer "F.Fab")
		)
		(fp_line
			(start -0.2794 0.9906)
			(end 0.2794 0.9906)
			(stroke
				(width 0.1)
				(type default)
			)
			(layer "F.Fab")
		)
		(pad "1" smd rect
			(at 0 0 90)
			(size 0.508 0.508)
			(layers "F.Cu" "F.Mask" "F.Paste")
			(net "P3V3_STBY")
		)
		(pad "2" smd rect
			(at 0 0.889 90)
			(size 0.508 0.508)
			(layers "F.Cu" "F.Mask" "F.Paste")
			(net "IRQ_BOARD_BMC_ALERT_N")
		)
		(zone
			(layer "F.Cu")
			(hatch none 0.5)
			(connect_pads
				(clearance 0)
			)
			(min_thickness 0.25)
			(keepout
				(tracks allowed)
				(vias not_allowed)
				(pads allowed)
				(copperpour not_allowed)
				(footprints allowed)
			)
			(placement
				(enabled no)
				(sheetname "")
			)
			(fill
				(thermal_gap 0.5)
				(thermal_bridge_width 0.5)
				(island_removal_mode 0)
			)
			(polygon
				(pts
					(xy 408.2415 -104.394) (xy 408.2415 -104.902) (xy 408.6225 -104.902) (xy 408.6225 -104.394)
				)
			)
		)
		(zone
			(layer "F.Cu")
			(hatch none 0.5)
			(connect_pads
				(clearance 0)
			)
			(min_thickness 0.25)
			(keepout
				(tracks not_allowed)
				(vias allowed)
				(pads allowed)
				(copperpour not_allowed)
				(footprints allowed)
			)
			(placement
				(enabled no)
				(sheetname "")
			)
			(fill
				(thermal_gap 0.5)
				(thermal_bridge_width 0.5)
				(island_removal_mode 0)
			)
			(polygon
				(pts
					(xy 408.6225 -104.394) (xy 408.6225 -104.902) (xy 408.2415 -104.902) (xy 408.2415 -104.394)
				)
			)
		)
	)
	(footprint ""
		(layer "F.Cu")
		(at 28.83408 -99.60102 90)
		(property "Reference" "C1C12"
			(at 0 0 90)
			(layer "F.SilkS")
			(hide yes)
			(effects
				(font
					(size 1.27 1.27)
				)
			)
		)
		(property "Value" ""
			(at 0 0 90)
			(layer "F.Fab")
			(effects
				(font
					(size 1.27 1.27)
				)
			)
		)
		(duplicate_pad_numbers_are_jumpers no)
		(fp_rect
			(start -0.3048 0.9906)
			(end 0.3048 -0.1016)
			(stroke
				(width 0)
				(type default)
			)
			(fill no)
			(layer "F.CrtYd")
		)
		(fp_line
			(start 0.3048 -0.1016)
			(end -0.3048 -0.1016)
			(stroke
				(width 0.1)
				(type default)
			)
			(layer "F.Fab")
		)
		(fp_line
			(start -0.3048 -0.1016)
			(end -0.3048 0.9906)
			(stroke
				(width 0.1)
				(type default)
			)
			(layer "F.Fab")
		)
		(fp_line
			(start 0.3048 0.9906)
			(end 0.3048 -0.1016)
			(stroke
				(width 0.1)
				(type default)
			)
			(layer "F.Fab")
		)
		(fp_line
			(start -0.3048 0.9906)
			(end 0.3048 0.9906)
			(stroke
				(width 0.1)
				(type default)
			)
			(layer "F.Fab")
		)
		(pad "1" smd rect
			(at 0 0 90)
			(size 0.508 0.508)
			(layers "F.Cu" "F.Mask" "F.Paste")
			(net "VR_PVSA_CPU1_BOOT")
		)
		(pad "2" smd rect
			(at 0 0.889 90)
			(size 0.508 0.508)
			(layers "F.Cu" "F.Mask" "F.Paste")
			(net "VR_PVSA_CPU1_PHASE")
		)
		(zone
			(layer "F.Cu")
			(hatch none 0.5)
			(connect_pads
				(clearance 0)
			)
			(min_thickness 0.25)
			(keepout
				(tracks not_allowed)
				(vias allowed)
				(pads allowed)
				(copperpour not_allowed)
				(footprints allowed)
			)
			(placement
				(enabled no)
				(sheetname "")
			)
			(fill
				(thermal_gap 0.5)
				(thermal_bridge_width 0.5)
				(island_removal_mode 0)
			)
			(polygon
				(pts
					(xy 29.46908 -99.34702) (xy 29.46908 -99.85502) (xy 29.08808 -99.85502) (xy 29.08808 -99.34702)
				)
			)
		)
		(zone
			(layer "F.Cu")
			(hatch none 0.5)
			(connect_pads
				(clearance 0)
			)
			(min_thickness 0.25)
			(keepout
				(tracks allowed)
				(vias not_allowed)
				(pads allowed)
				(copperpour not_allowed)
				(footprints allowed)
			)
			(placement
				(enabled no)
				(sheetname "")
			)
			(fill
				(thermal_gap 0.5)
				(thermal_bridge_width 0.5)
				(island_removal_mode 0)
			)
			(polygon
				(pts
					(xy 29.46908 -99.34702) (xy 29.46908 -99.85502) (xy 29.08808 -99.85502) (xy 29.08808 -99.34702)
				)
			)
		)
	)
)
